FILE_TYPE=LIBRARY_PARTS;
primitive 'MAX11617EEET';
  pin
    'AIN11||REF':
      PIN_NUMBER='(1)';
      BIDIRECTIONAL='TRUE';
      INPUT_LOAD='(-0.01,0.01)';
      OUTPUT_LOAD='(1.0,-1.0)';
    'AIN10':
      PIN_NUMBER='(2)';
      BIDIRECTIONAL='TRUE';
      INPUT_LOAD='(-0.01,0.01)';
      OUTPUT_LOAD='(1.0,-1.0)';
    'AIN9':
      PIN_NUMBER='(3)';
      BIDIRECTIONAL='TRUE';
      INPUT_LOAD='(-0.01,0.01)';
      OUTPUT_LOAD='(1.0,-1.0)';
    'AIN8':
      PIN_NUMBER='(4)';
      BIDIRECTIONAL='TRUE';
      INPUT_LOAD='(-0.01,0.01)';
      OUTPUT_LOAD='(1.0,-1.0)';
    'AIN0':
      PIN_NUMBER='(5)';
      BIDIRECTIONAL='TRUE';
      INPUT_LOAD='(-0.01,0.01)';
      OUTPUT_LOAD='(1.0,-1.0)';
    'AIN1':
      PIN_NUMBER='(6)';
      BIDIRECTIONAL='TRUE';
      INPUT_LOAD='(-0.01,0.01)';
      OUTPUT_LOAD='(1.0,-1.0)';
    'AIN2':
      PIN_NUMBER='(7)';
      BIDIRECTIONAL='TRUE';
      INPUT_LOAD='(-0.01,0.01)';
      OUTPUT_LOAD='(1.0,-1.0)';
    'AIN3':
      PIN_NUMBER='(8)';
      BIDIRECTIONAL='TRUE';
      INPUT_LOAD='(-0.01,0.01)';
      OUTPUT_LOAD='(1.0,-1.0)';
    'AIN4':
      PIN_NUMBER='(9)';
      BIDIRECTIONAL='TRUE';
      INPUT_LOAD='(-0.01,0.01)';
      OUTPUT_LOAD='(1.0,-1.0)';
    'AIN5':
      PIN_NUMBER='(10)';
      BIDIRECTIONAL='TRUE';
      INPUT_LOAD='(-0.01,0.01)';
      OUTPUT_LOAD='(1.0,-1.0)';
    'AIN6':
      PIN_NUMBER='(11)';
      BIDIRECTIONAL='TRUE';
      INPUT_LOAD='(-0.01,0.01)';
      OUTPUT_LOAD='(1.0,-1.0)';
    'AIN7':
      PIN_NUMBER='(12)';
      BIDIRECTIONAL='TRUE';
      INPUT_LOAD='(-0.01,0.01)';
      OUTPUT_LOAD='(1.0,-1.0)';
    'SCL':
      PIN_NUMBER='(13)';
      BIDIRECTIONAL='TRUE';
      INPUT_LOAD='(-0.01,0.01)';
      OUTPUT_LOAD='(1.0,-1.0)';
    'SDA':
      PIN_NUMBER='(14)';
      BIDIRECTIONAL='TRUE';
      INPUT_LOAD='(-0.01,0.01)';
      OUTPUT_LOAD='(1.0,-1.0)';
    'GND':
      PIN_NUMBER='(15)';
      PINUSE='POWER';
      NO_LOAD_CHECK='Both';
      NO_IO_CHECK='Both';
      NO_ASSERT_CHECK='TRUE';
      NO_DIR_CHECK='TRUE';
      ALLOW_CONNECT='TRUE';
    'VDD':
      PIN_NUMBER='(16)';
      PINUSE='POWER';
      NO_LOAD_CHECK='Both';
      NO_IO_CHECK='Both';
      NO_ASSERT_CHECK='TRUE';
      NO_DIR_CHECK='TRUE';
      ALLOW_CONNECT='TRUE';
  end_pin;
  body
    PART_NAME='MAX11617EEET';
    BODY_NAME='MAX11617EEET';
    PHYS_DES_PREFIX='U';
    CLASS='IC';
  end_body;
end_primitive;

END.
